FILE_TYPE = CONNECTIVITY;
{Allegro Design Entry HDL 17.4-2019 S026 (4007227) 1/17/2022}
"PAGE_NUMBER" = 188;
0"NC";
1"GND\g";
2"GND\g";
3"GND\g";
4"GND\g";
5"GND\g";
6"GND\g";
7"GND\g";
8"GND\g";
9"GND\g";
10"GND\g";
11"PVDDCR_CPU0_P1_VCCS";
12"PVDDCR_CPU0_P1_IMON6";
13"PVDDCR_CPU0_P1_PWM6";
14"PVDDCR_CPU0_P1_TEMP0";
15"NC_PVDDCR_CPU0_P1_DNC6";
16"PVDDCR_CPU0_P1_LSET6";
17"PVDDCR_CPU0_P1_VCC6";
18"PVDDCR_CPU0_P1_PWM5";
19"NC_PVDDCR_CPU0_P1_GL2_6";
20"NC_PVDDCR_CPU0_P1_GL1_6";
21"SW_PVDDCR_CPU0_P1_SW6_RC";
22"PVDDCR_CPU0_P1_IMON5";
23"PVDDCR_CPU0_P1_LSET5";
24"PVDDCR_CPU0_P1_TEMP0";
25"PVDDCR_CPU0_P1_VCC5";
26"NC_PVDDCR_CPU0_P1_DNC5";
27"IND_CPU0_P1_CPL6";
28"IND_CPU0_P1_CPL6";
29"IND_CPU0_P1_CPL5";
30"PVDDCR_CPU0_P1_VCCS";
31"SW_PVDDCR_CPU0_P1_SW5_RC";
32"NC_PVDDCR_CPU0_P1_GL2_5";
33"NC_PVDDCR_CPU0_P1_GL1_5";
34"PVDDCR_CPU0_P1\g";
35"GND\g";
36"PVDDCR_CPU0_P1\g";
37"GND\g";
38"PVDDCR_CPU0_P1_PVCC\g";
39"GND\g";
40"GND\g";
41"PVDDCR_CPU0_P1_PVCC\g";
42"GND\g";
43"SW_PVDDCR_CPU0_P1_SW6";
44"SW_PVDDCR_CPU0_P1_PH6";
45"PVDDCR_CPU0_P1_VOS6";
46"IND_CPU0_P1_CPL0";
47"SW_PVDDCR_CPU0_P1_BOOT6_RC";
48"SW_PVDDCR_CPU0_P1_BOOT6";
49"SW_PVDDCR_CPU0_P1_BOOT5_RC";
50"SW_PVDDCR_CPU0_P1_BOOT5";
51"GND\g";
52"SW_P12V_AUX_PVDDCR_CPU0_P1_FLT\g";
53"SW_PVDDCR_CPU0_P1_PH5";
54"SW_PVDDCR_CPU0_P1_SW5";
55"PVDDCR_CPU0_P1_VOS5";
56"SW_P12V_AUX_PVDDCR_CPU0_P1_FLT\g";
57"GND\g";
%"Q_CAP"
"1","(-7150,2300)","0","pure_quanta","I10";
;
LOCATION"PC125"
$SEC"1"
CDS_SEC"1"
MATERIAL"X6S"
TOLERANCE"10%"
VALUE"2.2UF"
VOLTAGE"10V"
PACK_TYPE"C0402"
CDS_LIB"pure_quanta"
PART_NUMBER"CH5222KEB01";
"B"
$PN"2"10;
"A"
$PN"1"17;
%"Q_RES"
"2","(-7150,2850)","0","pure_quanta","I12";
;
LOCATION"PR422"
$SEC"1"
CDS_SEC"1"
PACK_TYPE"0402LF"
VALUE"2.2"
TOLERANCE"1%"
WATTAGE"1/16W"
MATERIAL"CHIP"
CDS_LIB"pure_quanta"
PART_NUMBER"CS-2202FB01";
"A"
$PN"1"41;
"B"
$PN"2"17;
%"UNIVERSAL_GND"
"1","(-6800,2600)","0","pure_quanta_power","I13";
;
CDS_LIB"pure_quanta_power"
HDL_POWER"GND";
"A"1;
%"VCC_CORE"
"1","(-7150,3250)","0","pure_quanta_power","I14";
;
HDL_POWER"PVDDCR_CPU0_P1_PVCC"
CDS_LIB"pure_quanta_power";
"A"41;
%"Q_CAP"
"1","(-6800,2875)","0","pure_quanta","I15";
;
LOCATION"PC126_C0P1_6"
$SEC"1"
CDS_SEC"1"
VALUE"2.2UF"
PACK_TYPE"C0402"
VOLTAGE"10V"
TOLERANCE"10%"
MATERIAL"X6S"
CDS_LIB"pure_quanta"
PART_NUMBER"CH5222KEB01";
"B"
$PN"2"1;
"A"
$PN"1"41;
%"UNIVERSAL_GND"
"1","(-7525,4300)","0","pure_quanta_power","I16";
;
CDS_LIB"pure_quanta_power"
HDL_POWER"GND";
"A"2;
%"ISL99390FRZTR5935"
"1","(-5700,4850)","0","pure_quanta","I18";
;
LOCATION"PU29"
$SEC"1"
CDS_SEC"1"
PART_TYPE"SMLF"
MATERIAL"IC"
VALUE"ISL99390FRZ-TR5935"
CDS_LIB"pure_quanta"
NEEDS_NO_SIZE"TRUE"
CDS_LMAN_SYM_OUTLINE"-300,700,250,-650"
PART_NUMBER"AL099390004";
"PGND2"
$PN"7_9-20_24"39;
"GL2"
$PN"41"32;
"GL1"
$PN"6"33;
"DNC"
$PN"31"26;
"EN"
$PN"35"25;
"PGND3"
$PN"40"39;
"VOS"
$PN"1"55;
"VIN2"
$PN"30"52;
"PGND1"
$PN"5"39;
"SW"
$PN"10_19"54;
"LSET"
$PN"37"23;
"IOUT"
$PN"38"22;
"TOUT_FLT"
$PN"36"24;
"PVCC"
$PN"4"38;
"PHASE"
$PN"32"53;
"VIN1"
$PN"25_29"52;
"BOOT"
$PN"33"50;
"AGND"
$PN"2"39;
"VCC"
$PN"3"25;
"REFIN"
$PN"39"30;
"PWM"
$PN"34"18;
%"UNIVERSAL_GND"
"1","(-5100,1225)","0","pure_quanta_power","I19";
;
CDS_LIB"pure_quanta_power"
HDL_POWER"GND";
"A"40;
%"UNIVERSAL_GND"
"1","(-4225,1025)","0","pure_quanta_power","I20";
;
CDS_LIB"pure_quanta_power"
HDL_POWER"GND";
"A"3;
%"Q_RES"
"2","(-4225,1250)","0","pure_quanta","I21";
;
LOCATION"PR524"
$SEC"1"
CDS_SEC"1"
WATTAGE"1/8W"
MATERIAL"EMPTY"
VALUE"1.5"
PACK_TYPE"0402LF"
TOLERANCE"1%"
CDS_LIB"pure_quanta"
PART_NUMBER"CS-1504FB00";
"A"
$PN"1"21;
"B"
$PN"2"3;
%"Q_RES"
"1","(-3825,900)","0","pure_quanta","I22";
;
LOCATION"PR425"
$SEC"1"
CDS_SEC"1"
PACK_TYPE"0402LF"
VALUE"0"
MATERIAL"CHIP"
WATTAGE"1/16W"
TOLERANCE"5%"
CDS_LIB"pure_quanta"
PART_NUMBER"CS00002JB13";
"B"
$PN"2"36;
"A"
$PN"1"45;
%"Q_CAP"
"1","(-4225,1750)","0","pure_quanta","I23";
;
LOCATION"PC321"
$SEC"1"
CDS_SEC"1"
MATERIAL"EMPTY"
VOLTAGE"50V"
VALUE"560PF"
TOLERANCE"10%"
PACK_TYPE"C0402"
CDS_LIB"pure_quanta"
PART_NUMBER"CH1566K1B09";
"B"
$PN"2"21;
"A"
$PN"1"43;
%"UNIVERSAL_GND"
"1","(-3700,1575)","0","pure_quanta_power","I24";
;
CDS_LIB"pure_quanta_power"
HDL_POWER"GND";
"A"42;
%"Q_CAP"
"1","(-4900,2825)","0","pure_quanta","I25";
;
LOCATION"PC127_6"
$SEC"1"
CDS_SEC"1"
PACK_TYPE"0402"
VOLTAGE"25V"
MATERIAL"X7R"
TOLERANCE"10%"
VALUE"0.1UF"
CDS_LIB"pure_quanta"
PART_NUMBER"CH4104K1B00";
"B"
$PN"2"57;
"A"
$PN"1"56;
%"UNIVERSAL_GND"
"1","(-5150,4125)","0","pure_quanta_power","I26";
;
CDS_LIB"pure_quanta_power"
HDL_POWER"GND";
"A"39;
%"Q_CAP"
"1","(-4525,2825)","0","pure_quanta","I27";
;
LOCATION"PC128_6"
$SEC"1"
CDS_SEC"1"
PACK_TYPE"C0402"
MATERIAL"X6S"
TOLERANCE"10%"
VOLTAGE"25V"
VALUE"1UF"
CDS_LIB"pure_quanta"
PART_NUMBER"CH5104KEB02";
"B"
$PN"2"57;
"A"
$PN"1"56;
%"Q_RES"
"1","(-4250,2300)","0","pure_quanta","I28";
;
LOCATION"PR424"
$SEC"1"
CDS_SEC"1"
VALUE"5.6"
WATTAGE"1/16W"
PACK_TYPE"0402LF"
TOLERANCE"1%"
MATERIAL"CHIP"
CDS_LIB"pure_quanta"
PART_NUMBER"CS-5602FB01";
"B"
$PN"2"47;
"A"
$PN"1"48;
%"Q_CAP"
"1","(-4200,2825)","0","pure_quanta","I29";
;
LOCATION"PC129_6"
$SEC"1"
CDS_SEC"1"
PACK_TYPE"C0805"
MATERIAL"X6S"
VALUE"22UF"
VOLTAGE"16V"
TOLERANCE"20%"
CDS_LIB"pure_quanta"
PART_NUMBER"CH6223MEA01";
"B"
$PN"2"57;
"A"
$PN"1"56;
%"UNIVERSAL_GND"
"1","(-7475,1400)","0","pure_quanta_power","I3";
;
CDS_LIB"pure_quanta_power"
HDL_POWER"GND";
"A"4;
%"Q_CAP"
"1","(-3875,2825)","0","pure_quanta","I30";
;
LOCATION"PC130_6"
$SEC"1"
CDS_SEC"1"
PACK_TYPE"C0805"
MATERIAL"X6S"
VALUE"22UF"
VOLTAGE"16V"
TOLERANCE"20%"
CDS_LIB"pure_quanta"
PART_NUMBER"CH6223MEA01";
"B"
$PN"2"57;
"A"
$PN"1"56;
%"UNIVERSAL_GND"
"1","(-4275,3900)","0","pure_quanta_power","I31";
;
CDS_LIB"pure_quanta_power"
HDL_POWER"GND";
"A"5;
%"Q_RES"
"2","(-4275,4125)","0","pure_quanta","I32";
;
LOCATION"PR46"
$SEC"1"
CDS_SEC"1"
WATTAGE"1/8W"
MATERIAL"EMPTY"
TOLERANCE"1%"
VALUE"1.5"
PACK_TYPE"0402LF"
CDS_LIB"pure_quanta"
PART_NUMBER"CS-1504FB00";
"A"
$PN"1"31;
"B"
$PN"2"5;
%"Q_RES"
"1","(-3925,3750)","0","pure_quanta","I33";
;
LOCATION"PR204"
$SEC"1"
CDS_SEC"1"
VALUE"0"
MATERIAL"CHIP"
PACK_TYPE"0402LF"
WATTAGE"1/16W"
TOLERANCE"5%"
CDS_LIB"pure_quanta"
PART_NUMBER"CS00002JB13";
"B"
$PN"2"34;
"A"
$PN"1"55;
%"Q_CAP"
"1","(-7525,4575)","0","pure_quanta","I34";
;
LOCATION"PC306_5"
$SEC"1"
CDS_SEC"1"
PACK_TYPE"0402"
MATERIAL"X7R"
TOLERANCE"10%"
VOLTAGE"25V"
VALUE"0.1UF"
CDS_LIB"pure_quanta"
PART_NUMBER"CH4104K1B00";
"B"
$PN"2"2;
"A"
$PN"1"30;
%"UNIVERSAL_GND"
"1","(-7200,4375)","0","pure_quanta_power","I35";
;
CDS_LIB"pure_quanta_power"
HDL_POWER"GND";
"A"6;
%"Q_RES"
"1","(-6875,4550)","0","pure_quanta","I37";
;
LOCATION"PR202"
$SEC"1"
CDS_SEC"1"
PACK_TYPE"0402LF"
MATERIAL"EMPTY"
TOLERANCE"1%"
WATTAGE"1/16W"
VALUE"8.87K"
CDS_LIB"pure_quanta"
PART_NUMBER"CS28872FB01";
"B"
$PN"2"23;
"A"
$PN"1"6;
%"UNIVERSAL_GND"
"1","(-7200,5000)","0","pure_quanta_power","I38";
;
CDS_LIB"pure_quanta_power"
HDL_POWER"GND";
"A"7;
%"Q_CAP"
"1","(-7200,5200)","0","pure_quanta","I39";
;
LOCATION"PC307"
$SEC"1"
CDS_SEC"1"
MATERIAL"X6S"
TOLERANCE"10%"
VALUE"2.2UF"
VOLTAGE"10V"
PACK_TYPE"C0402"
CDS_LIB"pure_quanta"
PART_NUMBER"CH5222KEB01";
"B"
$PN"2"7;
"A"
$PN"1"25;
%"Q_CAP"
"1","(-7475,1675)","0","pure_quanta","I4";
;
LOCATION"PC124_6"
$SEC"1"
CDS_SEC"1"
MATERIAL"X7R"
TOLERANCE"10%"
VALUE"0.1UF"
VOLTAGE"25V"
PACK_TYPE"0402"
CDS_LIB"pure_quanta"
PART_NUMBER"CH4104K1B00";
"B"
$PN"2"4;
"A"
$PN"1"11;
%"Q_RES"
"2","(-7200,5750)","0","pure_quanta","I41";
;
LOCATION"PR201"
$SEC"1"
CDS_SEC"1"
PACK_TYPE"0402LF"
VALUE"2.2"
TOLERANCE"1%"
MATERIAL"CHIP"
WATTAGE"1/16W"
CDS_LIB"pure_quanta"
PART_NUMBER"CS-2202FB01";
"A"
$PN"1"38;
"B"
$PN"2"25;
%"UNIVERSAL_GND"
"1","(-6850,5500)","0","pure_quanta_power","I42";
;
CDS_LIB"pure_quanta_power"
HDL_POWER"GND";
"A"8;
%"Q_CAP"
"1","(-6850,5775)","0","pure_quanta","I43";
;
LOCATION"PC308_C0P1_5"
$SEC"1"
CDS_SEC"1"
MATERIAL"X6S"
TOLERANCE"10%"
VALUE"2.2UF"
VOLTAGE"10V"
PACK_TYPE"C0402"
CDS_LIB"pure_quanta"
PART_NUMBER"CH5222KEB01";
"B"
$PN"2"8;
"A"
$PN"1"38;
%"VCC_CORE"
"1","(-7200,6150)","0","pure_quanta_power","I44";
;
HDL_POWER"PVDDCR_CPU0_P1_PVCC"
CDS_LIB"pure_quanta_power";
"A"38;
%"Q_CAP"
"1","(-4950,5725)","0","pure_quanta","I45";
;
LOCATION"PC309_5"
$SEC"1"
CDS_SEC"1"
MATERIAL"X7R"
TOLERANCE"10%"
VALUE"0.1UF"
VOLTAGE"25V"
PACK_TYPE"0402"
CDS_LIB"pure_quanta"
PART_NUMBER"CH4104K1B00";
"B"
$PN"2"51;
"A"
$PN"1"52;
%"Q_CAP"
"1","(-4275,4650)","0","pure_quanta","I46";
;
LOCATION"PC318"
$SEC"1"
CDS_SEC"1"
MATERIAL"EMPTY"
TOLERANCE"10%"
VOLTAGE"50V"
VALUE"560PF"
PACK_TYPE"C0402"
CDS_LIB"pure_quanta"
PART_NUMBER"CH1566K1B09";
"B"
$PN"2"31;
"A"
$PN"1"54;
%"Q_RES"
"1","(-4300,5200)","0","pure_quanta","I47";
;
LOCATION"PR203"
$SEC"1"
CDS_SEC"1"
VALUE"5.6"
PACK_TYPE"0402LF"
WATTAGE"1/16W"
TOLERANCE"1%"
MATERIAL"CHIP"
CDS_LIB"pure_quanta"
PART_NUMBER"CS-5602FB01";
"B"
$PN"2"49;
"A"
$PN"1"50;
%"Q_CAP"
"1","(-4575,5725)","0","pure_quanta","I48";
;
LOCATION"PC310_5"
$SEC"1"
CDS_SEC"1"
PACK_TYPE"C0402"
MATERIAL"X6S"
TOLERANCE"10%"
VALUE"1UF"
VOLTAGE"25V"
CDS_LIB"pure_quanta"
PART_NUMBER"CH5104KEB02";
"B"
$PN"2"51;
"A"
$PN"1"52;
%"Q_CAP"
"1","(-4250,5725)","0","pure_quanta","I49";
;
LOCATION"PC311_5"
$SEC"1"
CDS_SEC"1"
MATERIAL"X6S"
PACK_TYPE"C0805"
VALUE"22UF"
VOLTAGE"16V"
TOLERANCE"20%"
CDS_LIB"pure_quanta"
PART_NUMBER"CH6223MEA01";
"B"
$PN"2"51;
"A"
$PN"1"52;
%"UNIVERSAL_GND"
"1","(-7150,1475)","0","pure_quanta_power","I5";
;
CDS_LIB"pure_quanta_power"
HDL_POWER"GND";
"A"9;
%"Q_CAP"
"1","(-3925,5725)","0","pure_quanta","I50";
;
LOCATION"PC312_5"
$SEC"1"
CDS_SEC"1"
MATERIAL"X6S"
VALUE"22UF"
VOLTAGE"16V"
TOLERANCE"20%"
PACK_TYPE"C0805"
CDS_LIB"pure_quanta"
PART_NUMBER"CH6223MEA01";
"B"
$PN"2"51;
"A"
$PN"1"52;
%"Q_INDUCTOR"
"1","(-3400,1725)","0","pure_quanta","I51";
;
LOCATION"PL27"
$SEC"1"
CDS_SEC"1"
VALUE"120NH/69A"
PACK_TYPE"SMLF"
MATERIAL"IND"
CDS_LIB"pure_quanta"
NEEDS_NO_SIZE"TRUE"
PART_NUMBER"CV+12^0EZ03";
"1"
$PN"1"42;
"2"
$PN"2"46;
%"Q_CAP"
"1","(-3275,2175)","0","pure_quanta","I52";
;
LOCATION"PC133"
$SEC"1"
CDS_SEC"1"
MATERIAL"X7R"
TOLERANCE"10%"
VALUE"0.22UF"
VOLTAGE"16V"
PACK_TYPE"0402"
CDS_LIB"pure_quanta"
PART_NUMBER"CH4223K1B00";
"B"
$PN"2"44;
"A"
$PN"1"47;
%"Q_INDUCTOR4P_14"
"1","(-2425,1825)","0","pure_quanta","I53";
;
LOCATION"PL8"
$SEC"1"
CDS_SEC"1"
PART_TYPE"SMLF"
MATERIAL"IND"
VALUE"150NH"
NEEDS_NO_SIZE"TRUE"
CDS_LIB"pure_quanta"
PART_NUMBER"CV+15^0TZ04";
"1"
$PN"1"43;
"4"
$PN"4"36;
"3"
$PN"3"27;
"2"
$PN"2"46;
%"UNIVERSAL_GND"
"1","(-3575,2475)","0","pure_quanta_power","I54";
;
CDS_LIB"pure_quanta_power"
HDL_POWER"GND";
"A"57;
%"Q_CAP"
"1","(-3575,2825)","0","pure_quanta","I55";
;
LOCATION"PC132_6"
$SEC"1"
CDS_SEC"1"
PACK_TYPE"C0805"
MATERIAL"X6S"
VALUE"22UF"
VOLTAGE"16V"
TOLERANCE"20%"
CDS_LIB"pure_quanta"
PART_NUMBER"CH6223MEA01";
"B"
$PN"2"57;
"A"
$PN"1"56;
%"VCC_CORE"
"1","(-3575,3125)","0","pure_quanta_power","I56";
;
HDL_POWER"SW_P12V_AUX_PVDDCR_CPU0_P1_FLT"
CDS_LIB"pure_quanta_power";
"A"56;
%"Q_CAP"
"1","(-1125,1775)","0","pure_quanta","I58";
;
LOCATION"PC134_6"
$SEC"1"
CDS_SEC"1"
VOLTAGE"4V"
VALUE"22UF"
TOLERANCE"20%"
MATERIAL"X6S"
PACK_TYPE"C0805"
CDS_LIB"pure_quanta"
PART_NUMBER"CH622KMEA03";
"B"
$PN"2"37;
"A"
$PN"1"36;
%"UNIVERSAL_GND"
"1","(-700,1425)","0","pure_quanta_power","I59";
;
CDS_LIB"pure_quanta_power"
HDL_POWER"GND";
"A"37;
%"Q_CAP"
"1","(-700,1775)","0","pure_quanta","I60";
;
LOCATION"PC135_6"
$SEC"1"
CDS_SEC"1"
VOLTAGE"4V"
TOLERANCE"20%"
MATERIAL"X6S"
PACK_TYPE"C0805"
VALUE"22UF"
CDS_LIB"pure_quanta"
PART_NUMBER"CH622KMEA03";
"B"
$PN"2"37;
"A"
$PN"1"36;
%"VCC_CORE"
"1","(-700,2100)","0","pure_quanta_power","I61";
;
HDL_POWER"PVDDCR_CPU0_P1"
CDS_LIB"pure_quanta_power";
"A"36;
%"Q_CAP"
"1","(-3325,5075)","0","pure_quanta","I63";
;
LOCATION"PC314"
$SEC"1"
CDS_SEC"1"
PACK_TYPE"0402"
VALUE"0.22UF"
VOLTAGE"16V"
TOLERANCE"10%"
MATERIAL"X7R"
CDS_LIB"pure_quanta"
PART_NUMBER"CH4223K1B00";
"B"
$PN"2"53;
"A"
$PN"1"49;
%"Q_INDUCTOR4P_14"
"1","(-2475,4725)","0","pure_quanta","I64";
;
LOCATION"PL33"
$SEC"1"
CDS_SEC"1"
PART_TYPE"SMLF"
VALUE"150NH"
MATERIAL"IND"
CDS_LIB"pure_quanta"
NEEDS_NO_SIZE"TRUE"
PART_NUMBER"CV+15^0TZ04";
"1"
$PN"1"54;
"4"
$PN"4"34;
"3"
$PN"3"29;
"2"
$PN"2"28;
%"UNIVERSAL_GND"
"1","(-3625,5375)","0","pure_quanta_power","I65";
;
CDS_LIB"pure_quanta_power"
HDL_POWER"GND";
"A"51;
%"Q_CAP"
"1","(-3625,5725)","0","pure_quanta","I66";
;
LOCATION"PC313_5"
$SEC"1"
CDS_SEC"1"
PACK_TYPE"C0805"
VALUE"22UF"
VOLTAGE"16V"
TOLERANCE"20%"
MATERIAL"X6S"
CDS_LIB"pure_quanta"
PART_NUMBER"CH6223MEA01";
"B"
$PN"2"51;
"A"
$PN"1"52;
%"VCC_CORE"
"1","(-3625,6025)","0","pure_quanta_power","I67";
;
HDL_POWER"SW_P12V_AUX_PVDDCR_CPU0_P1_FLT"
CDS_LIB"pure_quanta_power";
"A"52;
%"Q_CAP"
"1","(-1175,4675)","0","pure_quanta","I69";
;
LOCATION"PC315_5"
$SEC"1"
CDS_SEC"1"
VOLTAGE"4V"
VALUE"22UF"
TOLERANCE"20%"
MATERIAL"X6S"
PACK_TYPE"C0805"
CDS_LIB"pure_quanta"
PART_NUMBER"CH622KMEA03";
"B"
$PN"2"35;
"A"
$PN"1"34;
%"UNIVERSAL_GND"
"1","(-750,4325)","0","pure_quanta_power","I70";
;
CDS_LIB"pure_quanta_power"
HDL_POWER"GND";
"A"35;
%"Q_CAP"
"1","(-750,4675)","0","pure_quanta","I71";
;
LOCATION"PC316_5"
$SEC"1"
CDS_SEC"1"
VOLTAGE"4V"
VALUE"22UF"
TOLERANCE"20%"
MATERIAL"X6S"
PACK_TYPE"C0805"
CDS_LIB"pure_quanta"
PART_NUMBER"CH622KMEA03";
"B"
$PN"2"35;
"A"
$PN"1"34;
%"VCC_CORE"
"1","(-750,5000)","0","pure_quanta_power","I72";
;
HDL_POWER"PVDDCR_CPU0_P1"
CDS_LIB"pure_quanta_power";
"A"34;
%"ISL99390FRZTR5935"
"1","(-5650,1950)","0","pure_quanta","I73";
;
LOCATION"PU24"
$SEC"1"
CDS_SEC"1"
PART_TYPE"SMLF"
MATERIAL"IC"
VALUE"ISL99390FRZ-TR5935"
CDS_LIB"pure_quanta"
NEEDS_NO_SIZE"TRUE"
CDS_LMAN_SYM_OUTLINE"-300,700,250,-650"
PART_NUMBER"AL099390004";
"PGND2"
$PN"7_9-20_24"40;
"GL2"
$PN"41"19;
"GL1"
$PN"6"20;
"DNC"
$PN"31"15;
"EN"
$PN"35"17;
"PGND3"
$PN"40"40;
"VOS"
$PN"1"45;
"VIN2"
$PN"30"56;
"PGND1"
$PN"5"40;
"SW"
$PN"10_19"43;
"LSET"
$PN"37"16;
"IOUT"
$PN"38"12;
"TOUT_FLT"
$PN"36"14;
"PVCC"
$PN"4"41;
"PHASE"
$PN"32"44;
"VIN1"
$PN"25_29"56;
"BOOT"
$PN"33"48;
"AGND"
$PN"2"40;
"VCC"
$PN"3"17;
"REFIN"
$PN"39"11;
"PWM"
$PN"34"13;
%"Q_RES"
"1","(-6825,1650)","0","pure_quanta","I8";
;
LOCATION"PR423"
$SEC"1"
CDS_SEC"1"
WATTAGE"1/16W"
MATERIAL"EMPTY"
TOLERANCE"1%"
VALUE"8.87K"
PACK_TYPE"0402LF"
CDS_LIB"pure_quanta"
PART_NUMBER"CS28872FB01";
"B"
$PN"2"16;
"A"
$PN"1"9;
%"UNIVERSAL_GND"
"1","(-7150,2100)","0","pure_quanta_power","I9";
;
CDS_LIB"pure_quanta_power"
HDL_POWER"GND";
"A"10;
END.
